# S9S_MB_2U (Grand Teton) — schematic parts with pin connectivity, parts 5876–5876 of 6093; source: Cadence DE-HDL packaged netlist (pstxprt.dat, pstxnet.dat, pstchip.dat)

U1  SOCKET4677_AZIF0045P001C01CS  SOCKET4677_AZIF0045-P001C01CS IO  pkg SOCKET4677_82X64-5XA_H466  page 44  (pins 2944-3270 of 4677)
  DN27  DDR6_SB_DQS_DN6  BI  = M_G_CPU1_SB_DQS_DN<6>
  DN29  DDR6_SB_DQ8  BI  = M_G_CPU1_SB_DQ<8>
  DN31  DDR6_SB_DQ7  BI  = M_G_CPU1_SB_DQ<7>
  DN33  DDR6_SB_DQS_DP5  BI  = M_G_CPU1_SB_DQS_DP<5>
  DN35  DDR6_SB_DQ2  BI  = M_G_CPU1_SB_DQ<2>
  DN37  DDR7_SB_CS_N1  OUT  = M_H_CPU1_SB_CS_N<1>
  DN39  VSS957  POWER  = GND
  DN41  DDR7_SB_CA3  OUT  = M_H_CPU1_SB_CA<3>
  DN43  DDR6_SB_CA0  OUT  = M_G_CPU1_SB_CA<0>
  DN45  DDR6_CLK_DP0  OUT  = M_G_CPU1_CLK_DP<0>
  DN48  DDR5_A_RSP0  IN  = M_F_CPU1_SA_RSP<0>
  DN50  DDR6_SA_CA5  OUT  = M_G_CPU1_SA_CA<5>
  DN52  VSS959  POWER  = GND
  DN54  DDR6_SA_CS_N0  OUT  = M_G_CPU1_SA_CS_N<0>
  DN56  DDR6_SA_ECC7  BI  = M_G_CPU1_SA_CB<7>
  DN58  DDR6_SA_DQS_DP9  BI  = M_G_CPU1_SA_DQS_DP<9>
  DN60  DDR6_SA_ECC2  BI  = M_G_CPU1_SA_CB<2>
  DN62  DDR6_SA_DQ31  BI  = M_G_CPU1_SA_DQ<31>
  DN64  DDR6_SA_DQS_DP8  BI  = M_G_CPU1_SA_DQS_DP<8>
  DN66  DDR6_SA_DQ26  BI  = M_G_CPU1_SA_DQ<26>
  DN68  DDR6_SA_DQ15  BI  = M_G_CPU1_SA_DQ<15>
  DN70  DDR6_SA_DQS_DP6  BI  = M_G_CPU1_SA_DQS_DP<6>
  DN72  DDR6_SA_DQ10  BI  = M_G_CPU1_SA_DQ<10>
  DN74  DDR7_SA_DQ7  BI  = M_H_CPU1_SA_DQ<7>
  DN76  DDR7_SA_DQS_DP5  BI  = M_H_CPU1_SA_DQS_DP<5>
  DN78  VSS1143  POWER  = GND
  DN80  UPI3_TX_DP11  OUT  = NC
  DN82  UPI3_TX_DN9  OUT  = NC
  DN84  VSS1147  POWER  = GND
  DN86  PE3_TX_DP6  OUT  = P5E_CPU1_PE3_TX_DP<6>
  DN88  VSS1148  POWER  = GND
  DN90  PE3_RX_DN7  IN  = P5E_CPU1_PE3_RX_DN<7>
  DP2  UPI1_RX_DP7  IN  = UPI_CPU0_CPU1_P0P1_DP<7>
  DP4  VSS1152  POWER  = GND
  DP6  UPI1_TX_DN6  OUT  = UPI_CPU1_CPU0_P1P0_DN<6>
  DP8  VSS1157  POWER  = GND
  DP10  PE2_RX_DP8  IN  = P5E_CPU1_PE2_RX_DP<8>
  DP12  VSS966  POWER  = GND
  DP14  PE2_TX_DN9  OUT  = P5E_CPU1_PE2_TX_DN<9>
  DP16  VSS1149  POWER  = GND
  DP18  VSS968  POWER  = GND
  DP20  DDR7_SB_DQ22  BI  = M_H_CPU1_SB_DQ<22>
  DP22  DDR7_SB_DQ19  BI  = M_H_CPU1_SB_DQ<19>
  DP24  VSS969  POWER  = GND
  DP26  DDR6_SB_DQ14  BI  = M_G_CPU1_SB_DQ<14>
  DP28  DDR6_SB_DQ11  BI  = M_G_CPU1_SB_DQ<11>
  DP30  VSS1150  POWER  = GND
  DP32  DDR6_SB_DQ6  BI  = M_G_CPU1_SB_DQ<6>
  DP34  DDR6_SB_DQ3  BI  = M_G_CPU1_SB_DQ<3>
  DP36  VSS1151  POWER  = GND
  DP38  DDR7_SB_CS_N3  OUT  = M_H_CPU1_SB_CS_N<3>
  DP40  DDR7_SB_CA5  OUT  = M_H_CPU1_SB_CA<5>
  DP42  VSS973  POWER  = GND
  DP44  DDR6_SB_CA1  OUT  = M_G_CPU1_SB_CA<1>
  DP47  DDR5_A_RSP1  IN  = M_F_CPU1_SA_RSP<1>
  DP49  VSS1153  POWER  = GND
  DP51  DDR6_SA_CA3  OUT  = M_G_CPU1_SA_CA<3>
  DP53  DDR6_SA_CS_N1  OUT  = M_G_CPU1_SA_CS_N<1>
  DP55  VSS976  POWER  = GND
  DP57  DDR6_SA_ECC6  BI  = M_G_CPU1_SA_CB<6>
  DP59  DDR6_SA_ECC3  BI  = M_G_CPU1_SA_CB<3>
  DP61  VSS979  POWER  = GND
  DP63  DDR6_SA_DQ30  BI  = M_G_CPU1_SA_DQ<30>
  DP65  DDR6_SA_DQ27  BI  = M_G_CPU1_SA_DQ<27>
  DP67  VSS980  POWER  = GND
  DP69  DDR6_SA_DQ14  BI  = M_G_CPU1_SA_DQ<14>
  DP71  DDR6_SA_DQ11  BI  = M_G_CPU1_SA_DQ<11>
  DP73  VSS1154  POWER  = GND
  DP75  DDR7_SA_DQ6  BI  = M_H_CPU1_SA_DQ<6>
  DP77  DDR7_SA_DQ3  BI  = M_H_CPU1_SA_DQ<3>
  DP79  UPI3_TX_DN8  OUT  = NC
  DP81  VSS1159  POWER  = GND
  DP83  UPI3_TX_DP9  OUT  = NC
  DP85  PE3_TX_DN5  OUT  = P5E_CPU1_PE3_TX_DN<5>
  DP87  VSS1160  POWER  = GND
  DP89  PE3_RX_DN6  IN  = P5E_CPU1_PE3_RX_DN<6>
  DP91  VSS985  POWER  = GND
  DR1  VSS1162  POWER  = GND
  DR3  UPI1_RX_DP6  IN  = UPI_CPU0_CPU1_P0P1_DP<6>
  DR5  VSS998  POWER  = GND
  DR7  UPI1_TX_DP5  OUT  = UPI_CPU1_CPU0_P1P0_DP<5>
  DR9  VSS1187  POWER  = GND
  DR11  PE2_RX_DP9  IN  = P5E_CPU1_PE2_RX_DP<9>
  DR13  VSS1164  POWER  = GND
  DR15  PE2_TX_DP9  OUT  = P5E_CPU1_PE2_TX_DP<9>
  DR17  DDR5_SB_DQ31  BI  = M_F_CPU1_SB_DQ<31>
  DR19  VSS1166  POWER  = GND
  DR21  DDR7_SB_DQS_DN7  BI  = M_H_CPU1_SB_DQS_DN<7>
  DR23  VSS1169  POWER  = GND
  DR25  VSS990  POWER  = GND
  DR27  DDR6_SB_DQS_DP6  BI  = M_G_CPU1_SB_DQS_DP<6>
  DR29  VSS1172  POWER  = GND
  DR31  VSS1173  POWER  = GND
  DR33  DDR6_SB_DQS_DN5  BI  = M_G_CPU1_SB_DQS_DN<5>
  DR35  VSS993  POWER  = GND
  DR37  VSS1174  POWER  = GND
  DR39  DDR7_SB_PAR  OUT  = M_H_CPU1_SB_PAR
  DR41  VSS1175  POWER  = GND
  DR43  VSS1176  POWER  = GND
  DR45  DDR6_CLK_DN0  OUT  = M_G_CPU1_CLK_DN<0>
  DR48  VSS1177  POWER  = GND
  DR50  VSS1178  POWER  = GND
  DR52  DDR6_SA_CA1  OUT  = M_G_CPU1_SA_CA<1>
  DR54  VSS1000  POWER  = GND
  DR56  VSS1179  POWER  = GND
  DR58  DDR6_SA_DQS_DN9  BI  = M_G_CPU1_SA_DQS_DN<9>
  DR60  VSS1002  POWER  = GND
  DR62  VSS1003  POWER  = GND
  DR64  DDR6_SA_DQS_DN8  BI  = M_G_CPU1_SA_DQS_DN<8>
  DR66  VSS1181  POWER  = GND
  DR68  VSS1005  POWER  = GND
  DR70  DDR6_SA_DQS_DN6  BI  = M_G_CPU1_SA_DQS_DN<6>
  DR72  VSS1006  POWER  = GND
  DR74  VSS1182  POWER  = GND
  DR76  DDR7_SA_DQS_DN5  BI  = M_H_CPU1_SA_DQS_DN<5>
  DR78  VSS1183  POWER  = GND
  DR80  UPI3_TX_DP8  OUT  = NC
  DR82  UPI3_TX_DN7  OUT  = NC
  DR84  VSS1184  POWER  = GND
  DR86  PE3_TX_DP5  OUT  = P5E_CPU1_PE3_TX_DP<5>
  DR88  VSS1186  POWER  = GND
  DR90  PE3_RX_DP6  IN  = P5E_CPU1_PE3_RX_DP<6>
  DT2  UPI1_RX_DN6  IN  = UPI_CPU0_CPU1_P0P1_DN<6>
  DT4  VSS1021  POWER  = GND
  DT6  UPI1_TX_DN5  OUT  = UPI_CPU1_CPU0_P1P0_DN<5>
  DT8  VSS1207  POWER  = GND
  DT10  PE2_RX_DN9  IN  = P5E_CPU1_PE2_RX_DN<9>
  DT12  VSS1189  POWER  = GND
  DT14  PE2_TX_DP10  OUT  = P5E_CPU1_PE2_TX_DP<10>
  DT16  VSS1013  POWER  = GND
  DT18  DDR5_SB_DQS_DN3  BI  = M_F_CPU1_SB_DQS_DN<3>
  DT20  VSS1014  POWER  = GND
  DT22  VSS1190  POWER  = GND
  DT24  DDR6_SB_DQS_DP2  BI  = M_G_CPU1_SB_DQS_DP<2>
  DT26  VSS1016  POWER  = GND
  DT28  VSS1191  POWER  = GND
  DT30  DDR5_SB_DQS_DP0  BI  = M_F_CPU1_SB_DQS_DP<0>
  DT32  VSS1192  POWER  = GND
  DT34  VSS1194  POWER  = GND
  DT36  DDR6_SB_DQS_DP9  BI  = M_G_CPU1_SB_DQS_DP<9>
  DT38  VSS1196  POWER  = GND
  DT40  VSS1199  POWER  = GND
  DT42  DDR6_SB_CA6  OUT  = M_G_CPU1_SB_CA<6>
  DT44  VSS1023  POWER  = GND
  DT47  VSS1201  POWER  = GND
  DT49  DDR5_CLK_DP1  OUT  = M_F_CPU1_CLK_DP<1>
  DT51  VSS1025  POWER  = GND
  DT53  VSS1026  POWER  = GND
  DT55  DDR5_SA_DQS_DP3  BI  = M_F_CPU1_SA_DQS_DP<3>
  DT57  VSS1202  POWER  = GND
  DT59  VSS1028  POWER  = GND
  DT61  DDR6_SA_DQS_DN2  BI  = M_G_CPU1_SA_DQS_DN<2>
  DT63  VSS1029  POWER  = GND
  DT65  VSS1203  POWER  = GND
  DT67  DDR5_SA_DQS_DN1  BI  = M_F_CPU1_SA_DQS_DN<1>
  DT69  VSS1204  POWER  = GND
  DT71  VSS1205  POWER  = GND
  DT73  DDR6_SA_DQS_DP0  BI  = M_G_CPU1_SA_DQS_DP<0>
  DT75  VSS1206  POWER  = GND
  DT77  DDR7_SA_DQ1  BI  = M_H_CPU1_SA_DQ<1>
  DT79  VCCFA_EHV_FIVRA58  POWER  = PVCCFA_EHV_FIVRA_CPU1
  DT81  UPI3_TX_DP6  OUT  = NC
  DT83  VSS1036  POWER  = GND
  DT85  VCCFA_EHV_FIVRA59  POWER  = PVCCFA_EHV_FIVRA_CPU1
  DT87  PE3_TX_DN4  OUT  = P5E_CPU1_PE3_TX_DN<4>
  DT89  VCCFA_EHV_FIVRA60  POWER  = PVCCFA_EHV_FIVRA_CPU1
  DT91  PE3_RX_DP5  IN  = P5E_CPU1_PE3_RX_DP<5>
  DU1  UPI1_RX_DN5  IN  = UPI_CPU0_CPU1_P0P1_DN<5>
  DU3  VCCFA_EHV_FIVRA63  POWER  = PVCCFA_EHV_FIVRA_CPU1
  DU5  UPI1_TX_DP4  OUT  = UPI_CPU1_CPU0_P1P0_DP<4>
  DU7  VCCFA_EHV_FIVRA64  POWER  = PVCCFA_EHV_FIVRA_CPU1
  DU9  PE2_RX_DN10  IN  = P5E_CPU1_PE2_RX_DN<10>
  DU11  VCCFA_EHV_FIVRA61  POWER  = PVCCFA_EHV_FIVRA_CPU1
  DU13  PE2_TX_DN10  OUT  = P5E_CPU1_PE2_TX_DN<10>
  DU15  VCCFA_EHV_FIVRA62  POWER  = PVCCFA_EHV_FIVRA_CPU1
  DU17  DDR5_SB_DQ29  BI  = M_F_CPU1_SB_DQ<29>
  DU19  DDR5_SB_DQ25  BI  = M_F_CPU1_SB_DQ<25>
  DU21  VSS1209  POWER  = GND
  DU23  DDR6_SB_DQ20  BI  = M_G_CPU1_SB_DQ<20>
  DU25  DDR6_SB_DQ17  BI  = M_G_CPU1_SB_DQ<17>
  DU27  VSS1211  POWER  = GND
  DU29  DDR5_SB_DQ4  BI  = M_F_CPU1_SB_DQ<4>
  DU31  DDR5_SB_DQ1  BI  = M_F_CPU1_SB_DQ<1>
  DU33  VSS1212  POWER  = GND
  DU35  DDR6_SB_ECC0  BI  = M_G_CPU1_SB_CB<0>
  DU37  DDR6_SB_ECC5  BI  = M_G_CPU1_SB_CB<5>
  DU39  VSS1047  POWER  = GND
  DU41  DDR6_SB_CS_N2  OUT  = M_G_CPU1_SB_CS_N<2>
  DU43  DDR6_SB_CA4  OUT  = M_G_CPU1_SB_CA<4>
  DU45  VSS1048  POWER  = GND
  DU48  DDR6_B_RSP0  IN  = M_G_CPU1_SB_RSP<0>
  DU50  DDR5_SB_CA1  OUT  = M_F_CPU1_SB_CA<1>
  DU52  VSS1050  POWER  = GND
  DU54  DDR5_SA_DQ28  BI  = M_F_CPU1_SA_DQ<28>
  DU56  DDR5_SA_DQ25  BI  = M_F_CPU1_SA_DQ<25>
  DU58  VSS1051  POWER  = GND
  DU60  DDR6_SA_DQ20  BI  = M_G_CPU1_SA_DQ<20>
  DU62  DDR6_SA_DQ17  BI  = M_G_CPU1_SA_DQ<17>
  DU64  VSS1052  POWER  = GND
  DU66  DDR5_SA_DQ12  BI  = M_F_CPU1_SA_DQ<12>
  DU68  DDR5_SA_DQ9  BI  = M_F_CPU1_SA_DQ<9>
  DU70  VSS1054  POWER  = GND
  DU72  DDR6_SA_DQ4  BI  = M_G_CPU1_SA_DQ<4>
  DU74  DDR6_SA_DQ1  BI  = M_G_CPU1_SA_DQ<1>
  DU76  VSS1213  POWER  = GND
  DU78  VSS1214  POWER  = GND
  DU80  UPI3_TX_DN6  OUT  = NC
  DU82  UPI3_TX_DP7  OUT  = NC
  DU84  VSS1215  POWER  = GND
  DU86  PE3_TX_DP4  OUT  = P5E_CPU1_PE3_TX_DP<4>
  DU88  VSS1216  POWER  = GND
  DU90  PE3_RX_DN5  IN  = P5E_CPU1_PE3_RX_DN<5>
  DV2  UPI1_RX_DP5  IN  = UPI_CPU0_CPU1_P0P1_DP<5>
  DV4  VSS1063  POWER  = GND
  DV6  UPI1_TX_DN4  OUT  = UPI_CPU1_CPU0_P1P0_DN<4>
  DV8  VSS1221  POWER  = GND
  DV10  PE2_RX_DP10  IN  = P5E_CPU1_PE2_RX_DP<10>
  DV12  VSS1059  POWER  = GND
  DV14  PE2_TX_DN11  OUT  = P5E_CPU1_PE2_TX_DN<11>
  DV16  VSS1060  POWER  = GND
  DV18  DDR5_SB_DQS_DP3  BI  = M_F_CPU1_SB_DQS_DP<3>
  DV20  DDR5_SB_DQ24  BI  = M_F_CPU1_SB_DQ<24>
  DV22  DDR6_SB_DQ21  BI  = M_G_CPU1_SB_DQ<21>
  DV24  DDR6_SB_DQS_DN2  BI  = M_G_CPU1_SB_DQS_DN<2>
  DV26  DDR6_SB_DQ16  BI  = M_G_CPU1_SB_DQ<16>
  DV28  DDR5_SB_DQ5  BI  = M_F_CPU1_SB_DQ<5>
  DV30  DDR5_SB_DQS_DN0  BI  = M_F_CPU1_SB_DQS_DN<0>
  DV32  DDR5_SB_DQ0  BI  = M_F_CPU1_SB_DQ<0>
  DV34  DDR6_SB_ECC1  BI  = M_G_CPU1_SB_CB<1>
  DV36  DDR6_SB_DQS_DN9  BI  = M_G_CPU1_SB_DQS_DN<9>
  DV38  DDR6_SB_ECC4  BI  = M_G_CPU1_SB_CB<4>
  DV40  DDR6_SB_CS_N3  OUT  = M_G_CPU1_SB_CS_N<3>
  DV42  VSS1064  POWER  = GND
  DV44  DDR6_SB_CA2  OUT  = M_G_CPU1_SB_CA<2>
  DV47  DDR6_B_RSP1  IN  = M_G_CPU1_SB_RSP<1>
  DV49  DDR5_CLK_DN1  OUT  = M_F_CPU1_CLK_DN<1>
  DV51  DDR5_SB_CA0  OUT  = M_F_CPU1_SB_CA<0>
  DV53  DDR5_SA_DQ29  BI  = M_F_CPU1_SA_DQ<29>
  DV55  DDR5_SA_DQS_DN3  BI  = M_F_CPU1_SA_DQS_DN<3>
  DV57  DDR5_SA_DQ24  BI  = M_F_CPU1_SA_DQ<24>
  DV59  DDR6_SA_DQ21  BI  = M_G_CPU1_SA_DQ<21>
  DV61  DDR6_SA_DQS_DP2  BI  = M_G_CPU1_SA_DQS_DP<2>
  DV63  DDR6_SA_DQ16  BI  = M_G_CPU1_SA_DQ<16>
  DV65  DDR5_SA_DQ13  BI  = M_F_CPU1_SA_DQ<13>
  DV67  DDR5_SA_DQS_DP1  BI  = M_F_CPU1_SA_DQS_DP<1>
  DV69  DDR5_SA_DQ8  BI  = M_F_CPU1_SA_DQ<8>
  DV71  DDR6_SA_DQ5  BI  = M_G_CPU1_SA_DQ<5>
  DV73  DDR6_SA_DQS_DN0  BI  = M_G_CPU1_SA_DQS_DN<0>
  DV75  DDR6_SA_DQ0  BI  = M_G_CPU1_SA_DQ<0>
  DV77  VSS1218  POWER  = GND
  DV79  VSS1219  POWER  = GND
  DV81  VSS1222  POWER  = GND
  DV83  VSS1226  POWER  = GND
  DV85  PE3_TX_DN3  OUT  = P5E_CPU1_PE3_TX_DN<3>
  DV87  VSS1227  POWER  = GND
  DV89  PE3_RX_DN4  IN  = P5E_CPU1_PE3_RX_DN<4>
  DV91  VSS1228  POWER  = GND
  DW1  VSS1229  POWER  = GND
  DW3  UPI1_RX_DP4  IN  = UPI_CPU0_CPU1_P0P1_DP<4>
  DW5  VSS1249  POWER  = GND
  DW7  UPI1_TX_DP3  OUT  = UPI_CPU1_CPU0_P1P0_DP<3>
  DW9  VSS1268  POWER  = GND
  DW11  PE2_RX_DP11  IN  = P5E_CPU1_PE2_RX_DP<11>
  DW13  VSS1230  POWER  = GND
  DW15  PE2_TX_DP11  OUT  = P5E_CPU1_PE2_TX_DP<11>
  DW17  VSS1231  POWER  = GND
  DW19  VSS1233  POWER  = GND
  DW21  VSS1077  POWER  = GND
  DW23  VSS1234  POWER  = GND
  DW25  VSS1236  POWER  = GND
  DW27  VSS1238  POWER  = GND
  DW29  VSS1239  POWER  = GND
  DW31  VSS1240  POWER  = GND
  DW33  VSS1241  POWER  = GND
  DW35  VSS1242  POWER  = GND
  DW37  VSS1243  POWER  = GND
  DW39  VSS1244  POWER  = GND
  DW41  VSS1245  POWER  = GND
  DW43  VSS1246  POWER  = GND
  DW45  VSS1247  POWER  = GND
  DW48  VSS1248  POWER  = GND
  DW50  VSS1250  POWER  = GND
  DW52  VSS1251  POWER  = GND
  DW54  VSS1252  POWER  = GND
  DW56  VSS1253  POWER  = GND
  DW58  VSS1254  POWER  = GND
  DW60  VSS1097  POWER  = GND
  DW62  VSS1255  POWER  = GND
  DW64  VSS1256  POWER  = GND
  DW66  VSS1257  POWER  = GND
  DW68  VSS1258  POWER  = GND
  DW70  VSS1259  POWER  = GND
  DW72  VSS1260  POWER  = GND
  DW74  VSS1261  POWER  = GND
  DW76  VSS1262  POWER  = GND
  DW78  DDR7_SA_DQ2  BI  = M_H_CPU1_SA_DQ<2>
  DW80  VSS1263  POWER  = GND
  DW82  VSS1264  POWER  = GND
  DW84  VSS1266  POWER  = GND
  DW86  PE3_TX_DP3  OUT  = P5E_CPU1_PE3_TX_DP<3>
  DW88  VSS1267  POWER  = GND
  DW90  PE3_RX_DP4  IN  = P5E_CPU1_PE3_RX_DP<4>
  DY2  UPI1_RX_DN4  IN  = UPI_CPU0_CPU1_P0P1_DN<4>
  DY4  VSS1115  POWER  = GND
  DY6  UPI1_TX_DN3  OUT  = UPI_CPU1_CPU0_P1P0_DN<3>
  DY8  VSS1270  POWER  = GND
  DY10  PE2_RX_DN11  IN  = P5E_CPU1_PE2_RX_DN<11>
  DY12  VSS1111  POWER  = GND
  DY14  PE2_TX_DP12  OUT  = P5E_CPU1_PE2_TX_DP<12>
  DY16  VSS1112  POWER  = GND
  DY18  DDR5_SB_DQS_DN8  BI  = M_F_CPU1_SB_DQS_DN<8>
  DY20  DDR5_SB_DQ26  BI  = M_F_CPU1_SB_DQ<26>
  DY22  DDR6_SB_DQ23  BI  = M_G_CPU1_SB_DQ<23>
  DY24  DDR6_SB_DQS_DP7  BI  = M_G_CPU1_SB_DQS_DP<7>
  DY26  DDR6_SB_DQ18  BI  = M_G_CPU1_SB_DQ<18>
  DY28  DDR5_SB_DQ7  BI  = M_F_CPU1_SB_DQ<7>
  DY30  DDR5_SB_DQS_DP5  BI  = M_F_CPU1_SB_DQS_DP<5>
  DY32  DDR5_SB_DQ2  BI  = M_F_CPU1_SB_DQ<2>
  DY34  DDR6_SB_ECC3  BI  = M_G_CPU1_SB_CB<3>
  DY36  DDR6_SB_DQS_DP4  BI  = M_G_CPU1_SB_DQS_DP<4>
  DY38  DDR6_SB_ECC6  BI  = M_G_CPU1_SB_CB<6>
  DY40  DDR6_SB_CS_N1  OUT  = M_G_CPU1_SB_CS_N<1>
  DY42  VSS1116  POWER  = GND
  DY44  DDR6_SB_CA3  OUT  = M_G_CPU1_SB_CA<3>
  DY47  DDR6_A_RSP1  IN  = M_G_CPU1_SA_RSP<1>
  DY49  DDR5_CLK_DN0  OUT  = M_F_CPU1_CLK_DN<0>
  DY51  DDR5_SA_CA6  OUT  = M_F_CPU1_SA_CA<6>
